#ISCELL
  pure_quanta quanta_title_block_c *
  *
#CELL
  pure_quanta genoa_sp5 *
  page25_i147
#CELL
  pure_quanta genoa_sp5 *
  page25_i148
#ISCELL
  standard offpage *
  page25_i149
#ISCELL
  standard offpage *
  page25_i150
#ISCELL
  mstr_standard tap *
  page25_i151
#ISCELL
  mstr_standard tap *
  page25_i152
#ISCELL
  mstr_standard tap *
  page25_i153
#ISCELL
  mstr_standard tap *
  page25_i154
#ISCELL
  standard tap *
  page25_i155
#ISCELL
  standard tap *
  page25_i156
#ISCELL
  standard tap *
  page25_i157
#ISCELL
  standard tap *
  page25_i158
#ISCELL
  standard tap *
  page25_i159
#ISCELL
  standard tap *
  page25_i160
#ISCELL
  standard tap *
  page25_i161
#ISCELL
  standard tap *
  page25_i162
#ISCELL
  standard tap *
  page25_i163
#ISCELL
  standard tap *
  page25_i164
#ISCELL
  standard tap *
  page25_i165
#ISCELL
  standard tap *
  page25_i166
#ISCELL
  standard tap *
  page25_i167
#ISCELL
  standard tap *
  page25_i168
#ISCELL
  standard tap *
  page25_i169
#ISCELL
  standard tap *
  page25_i170
#ISCELL
  standard tap *
  page25_i171
#ISCELL
  standard tap *
  page25_i172
#ISCELL
  standard tap *
  page25_i173
#ISCELL
  standard tap *
  page25_i174
#ISCELL
  standard tap *
  page25_i175
#ISCELL
  standard tap *
  page25_i176
#ISCELL
  standard tap *
  page25_i177
#ISCELL
  standard tap *
  page25_i178
#ISCELL
  standard tap *
  page25_i179
#ISCELL
  standard tap *
  page25_i180
#ISCELL
  standard tap *
  page25_i181
#ISCELL
  standard tap *
  page25_i182
#ISCELL
  standard offpage *
  page25_i217
#ISCELL
  standard offpage *
  page25_i218
#ISCELL
  standard offpage *
  page25_i283
#ISCELL
  standard offpage *
  page25_i284
#ISCELL
  standard tap *
  page25_i285
#ISCELL
  standard tap *
  page25_i286
#ISCELL
  standard tap *
  page25_i287
#ISCELL
  standard tap *
  page25_i288
#ISCELL
  standard offpage *
  page25_i293
#ISCELL
  standard tap *
  page25_i299
#ISCELL
  standard tap *
  page25_i300
#ISCELL
  standard tap *
  page25_i301
#ISCELL
  standard tap *
  page25_i302
#ISCELL
  standard offpage *
  page25_i304
#ISCELL
  standard offpage *
  page25_i315
#ISCELL
  standard tap *
  page25_i316
#ISCELL
  standard tap *
  page25_i317
#ISCELL
  standard tap *
  page25_i318
#ISCELL
  standard tap *
  page25_i319
#ISCELL
  standard tap *
  page25_i320
#ISCELL
  standard tap *
  page25_i321
#ISCELL
  standard tap *
  page25_i322
#ISCELL
  standard tap *
  page25_i323
#ISCELL
  standard offpage *
  page25_i324
#ISCELL
  mstr_standard tap *
  page25_i325
#ISCELL
  mstr_standard tap *
  page25_i326
#ISCELL
  mstr_standard tap *
  page25_i327
#ISCELL
  mstr_standard tap *
  page25_i328
#ISCELL
  mstr_standard tap *
  page25_i329
#ISCELL
  standard tap *
  page25_i330
#ISCELL
  standard tap *
  page25_i331
#ISCELL
  standard tap *
  page25_i332
#ISCELL
  standard tap *
  page25_i333
#ISCELL
  standard tap *
  page25_i334
#ISCELL
  standard tap *
  page25_i335
#ISCELL
  standard tap *
  page25_i336
#ISCELL
  standard tap *
  page25_i337
#ISCELL
  standard tap *
  page25_i338
#ISCELL
  standard tap *
  page25_i339
#ISCELL
  standard tap *
  page25_i340
#ISCELL
  standard tap *
  page25_i341
#ISCELL
  standard tap *
  page25_i342
#ISCELL
  standard tap *
  page25_i343
#ISCELL
  standard tap *
  page25_i344
#ISCELL
  standard tap *
  page25_i345
#ISCELL
  standard tap *
  page25_i346
#ISCELL
  standard tap *
  page25_i347
#ISCELL
  standard tap *
  page25_i348
#ISCELL
  standard tap *
  page25_i349
#ISCELL
  standard tap *
  page25_i350
#ISCELL
  standard tap *
  page25_i351
#ISCELL
  standard tap *
  page25_i352
#ISCELL
  standard tap *
  page25_i353
#ISCELL
  standard tap *
  page25_i354
#ISCELL
  standard tap *
  page25_i355
#ISCELL
  standard tap *
  page25_i356
#ISCELL
  standard offpage *
  page25_i357
#ISCELL
  standard offpage *
  page25_i358
#ISCELL
  standard tap *
  page25_i382
#ISCELL
  standard tap *
  page25_i383
#ISCELL
  standard tap *
  page25_i387
#ISCELL
  standard tap *
  page25_i388
#ISCELL
  standard tap *
  page25_i389
#ISCELL
  standard tap *
  page25_i390
#ISCELL
  standard tap *
  page25_i392
#ISCELL
  standard tap *
  page25_i393
#ISCELL
  standard offpage *
  page25_i398
#ISCELL
  standard tap *
  page25_i399
#ISCELL
  standard tap *
  page25_i400
#ISCELL
  standard tap *
  page25_i401
#ISCELL
  standard tap *
  page25_i402
#ISCELL
  standard offpage *
  page25_i403
#ISCELL
  standard tap *
  page25_i404
#ISCELL
  standard tap *
  page25_i406
#ISCELL
  standard tap *
  page25_i407
#ISCELL
  standard tap *
  page25_i408
#ISCELL
  standard offpage *
  page25_i410
#ISCELL
  standard offpage *
  page25_i411
